FILE_TYPE = MULTI_PHYS_TABLE;

PART 'SOCKET4677_AZIF0045P001C01CS'

{========================================================================================}
:VALUE                           | PART_TYPE | MATERIAL | PART_NUMBER    = STANDARD | LIFECYCLE          | PART_NUMBER   | JEDEC_TYPE                  | DESCRIPTION                         | MANUFTR | MANUF_PN             | RD_CMPLS_LVL | CMPLS_LVL | CLASS | DIP_SMD | FROM_PJ    | DATA                         | FP_ECN                   | EE_CHECK_LIST | CREATOR | CREATEDAY  | PSL | STATUS | ESD_CDM | ESD_HBM | ESD_MM | MSD | PIN_LENGTH_LONG_PIN | PIN_LENGTH_SHORT_PIN ;
{========================================================================================}
 'SOCKET4677_AZIF0045-P001C01CS' | 'SMLF'    | 'IO'     | 'DGA^7000023'(!) = ''       | ''               | 'DGA^7000023' |'SOCKET4677_82X64-5XA_H466'| 'SOCKET 4677P E LGA(P0.9398,H8.64)' | 'LTS'   | 'AZIF0045-P001C01CS' | 'EP(V1)'     | 'EP(V1)'  | 'IO'  | ''      | 'F0T-IVES' | 'LTS_AZIF0045-P001C01CS.pdf' | 'AZIF0045-P001C01CS.msg' | ''            | ''      | '20211209' | ''  | ''     | ''      | ''      | ''     | ''  | '0 MILS'            | '0 MILS'            
 'SOCKET4677_AZIF0045-P001C01CS' | 'SMLF'    | 'EMPTY'  | 'DGA^7000023'(!) = ''       | ''               | 'DGA^7000023' |'SOCKET4677_82X64-5XA_H466'| 'SOCKET 4677P E LGA(P0.9398,H8.64)' | 'LTS'   | 'AZIF0045-P001C01CS' | 'EP(V1)'     | 'EP(V1)'  | 'IO'  | ''      | 'F0T-IVES' | 'LTS_AZIF0045-P001C01CS.pdf' | 'AZIF0045-P001C01CS.msg' | ''            | ''      | '20211209' | ''  | ''     | ''      | ''      | ''     | ''  | '0 MILS'            | '0 MILS'            

END_PART

END.

